(kicad_pcb
	(version 20260206)
	(generator "pcbnew")
	(generator_version "10.0")
	(general
		(thickness 1.6)
		(legacy_teardrops no)
	)
	(paper "A4")
	(title_block
		(title "04192023_DAF0TMB3IC0_F0TG_MB_C_brd_V02_OCP.brd")
		(comment 1 "Grand Teton / footprints 6146-6152 of 8354")
	)
	(layers
		(0 "F.Cu" signal "TOP")
		(4 "In1.Cu" signal "GND")
		(6 "In2.Cu" signal "IN1")
		(8 "In3.Cu" signal "GND1")
		(10 "In4.Cu" signal "IN2")
		(12 "In5.Cu" signal "GND2")
		(14 "In6.Cu" signal "IN3")
		(16 "In7.Cu" signal "GND3")
		(18 "In8.Cu" signal "VCC")
		(20 "In9.Cu" signal "VCC1")
		(22 "In10.Cu" signal "GND4")
		(24 "In11.Cu" signal "IN4")
		(26 "In12.Cu" signal "GND5")
		(28 "In13.Cu" signal "IN5")
		(30 "In14.Cu" signal "GND6")
		(32 "In15.Cu" signal "IN6")
		(34 "In16.Cu" signal "GND7")
		(2 "B.Cu" signal "BOTTOM")
		(9 "F.Adhes" user "F.Adhesive")
		(11 "B.Adhes" user "B.Adhesive")
		(13 "F.Paste" user "Package Geometry/Pastemask Top")
		(15 "B.Paste" user "Package Geometry/Pastemask Bottom")
		(5 "F.SilkS" user "Ref Des/Silkscreen Top")
		(7 "B.SilkS" user "Ref Des/Silkscreen Bottom")
		(1 "F.Mask" user "Board Geometry/Soldermask Top")
		(3 "B.Mask" user "Board Geometry/Soldermask Bottom")
		(17 "Dwgs.User" user "User.Drawings")
		(19 "Cmts.User" user "User.Comments")
		(21 "Eco1.User" user "User.Eco1")
		(23 "Eco2.User" user "User.Eco2")
		(25 "Edge.Cuts" user "Board Geometry/Outline")
		(27 "Margin" user)
		(31 "F.CrtYd" user "Package Geometry/Place Bound Top")
		(29 "B.CrtYd" user "Package Geometry/Place Bound Bottom")
		(35 "F.Fab" user "Ref Des/Assembly Top")
		(33 "B.Fab" user "Ref Des/Assembly Bottom")
	)
	(footprint ""
		(layer "B.Cu")
		(at 372.878604 -395.148562 90)
		(property "Reference" "C1013"
			(at 0 0 90)
			(layer "B.SilkS")
			(hide yes)
			(effects
				(font
					(size 1.27 1.27)
				)
				(justify mirror)
			)
		)
		(property "Value" ""
			(at 0 0 90)
			(layer "B.Fab")
			(effects
				(font
					(size 1.27 1.27)
				)
				(justify mirror)
			)
		)
		(duplicate_pad_numbers_are_jumpers no)
		(fp_line
			(start 0.299974 -0.150114)
			(end -0.299974 -0.150114)
			(stroke
				(width 0.1)
				(type default)
			)
			(layer "B.Fab")
		)
		(fp_line
			(start -0.299974 -0.150114)
			(end -0.299974 0.150114)
			(stroke
				(width 0.1)
				(type default)
			)
			(layer "B.Fab")
		)
		(fp_line
			(start 0.299974 0.150114)
			(end 0.299974 -0.150114)
			(stroke
				(width 0.1)
				(type default)
			)
			(layer "B.Fab")
		)
		(fp_line
			(start -0.299974 0.150114)
			(end 0.299974 0.150114)
			(stroke
				(width 0.1)
				(type default)
			)
			(layer "B.Fab")
		)
		(pad "1" smd rect
			(at 0.2667 0 270)
			(size 0.3048 0.381)
			(layers "B.Cu" "B.Mask" "B.Paste")
			(net "P0V9_CPU0_RT3_2A")
		)
		(pad "2" smd rect
			(at -0.2667 0 270)
			(size 0.3048 0.381)
			(layers "B.Cu" "B.Mask" "B.Paste")
			(net "GND")
		)
	)
	(footprint ""
		(layer "B.Cu")
		(at 63.619634 -196.186552 180)
		(property "Reference" "R514"
			(at 0 0 0)
			(layer "B.SilkS")
			(hide yes)
			(effects
				(font
					(size 1.27 1.27)
				)
				(justify mirror)
			)
		)
		(property "Value" ""
			(at 0 0 0)
			(layer "B.Fab")
			(effects
				(font
					(size 1.27 1.27)
				)
				(justify mirror)
			)
		)
		(duplicate_pad_numbers_are_jumpers no)
		(fp_line
			(start 0.7874 0.4064)
			(end 0.7874 -0.4064)
			(stroke
				(width 0.1524)
				(type default)
			)
			(layer "B.SilkS")
		)
		(fp_line
			(start 0.7874 -0.4064)
			(end -0.7874 -0.4064)
			(stroke
				(width 0.1524)
				(type default)
			)
			(layer "B.SilkS")
		)
		(fp_line
			(start -0.7874 0.4064)
			(end 0.7874 0.4064)
			(stroke
				(width 0.1524)
				(type default)
			)
			(layer "B.SilkS")
		)
		(fp_line
			(start -0.7874 -0.4064)
			(end -0.7874 0.4064)
			(stroke
				(width 0.1524)
				(type default)
			)
			(layer "B.SilkS")
		)
		(fp_line
			(start 0.67945 0.3048)
			(end 0.67945 -0.305054)
			(stroke
				(width 0.1)
				(type default)
			)
			(layer "B.Fab")
		)
		(fp_line
			(start 0.67945 -0.305054)
			(end 0.12065 -0.305054)
			(stroke
				(width 0.1)
				(type default)
			)
			(layer "B.Fab")
		)
		(fp_line
			(start 0.12065 0.3048)
			(end 0.67945 0.3048)
			(stroke
				(width 0.1)
				(type default)
			)
			(layer "B.Fab")
		)
		(fp_line
			(start 0.12065 0.2794)
			(end 0.12065 0.3048)
			(stroke
				(width 0.1)
				(type default)
			)
			(layer "B.Fab")
		)
		(fp_line
			(start 0.12065 -0.2794)
			(end -0.12065 -0.2794)
			(stroke
				(width 0.1)
				(type default)
			)
			(layer "B.Fab")
		)
		(fp_line
			(start 0.12065 -0.305054)
			(end 0.12065 -0.2794)
			(stroke
				(width 0.1)
				(type default)
			)
			(layer "B.Fab")
		)
		(fp_line
			(start -0.120396 0.3048)
			(end -0.120396 0.2794)
			(stroke
				(width 0.1)
				(type default)
			)
			(layer "B.Fab")
		)
		(fp_line
			(start -0.120396 0.2794)
			(end 0.12065 0.2794)
			(stroke
				(width 0.1)
				(type default)
			)
			(layer "B.Fab")
		)
		(fp_line
			(start -0.12065 -0.2794)
			(end -0.12065 -0.3048)
			(stroke
				(width 0.1)
				(type default)
			)
			(layer "B.Fab")
		)
		(fp_line
			(start -0.12065 -0.3048)
			(end -0.67945 -0.3048)
			(stroke
				(width 0.1)
				(type default)
			)
			(layer "B.Fab")
		)
		(fp_line
			(start -0.67945 0.3048)
			(end -0.120396 0.3048)
			(stroke
				(width 0.1)
				(type default)
			)
			(layer "B.Fab")
		)
		(fp_line
			(start -0.67945 -0.3048)
			(end -0.67945 0.3048)
			(stroke
				(width 0.1)
				(type default)
			)
			(layer "B.Fab")
		)
		(pad "1" smd circle
			(at 0.40005 0)
			(size 0 0)
			(layers "B.Cu" "B.Mask" "B.Paste")
			(net "P3V3_AUX")
		)
		(pad "2" smd circle
			(at -0.40005 0)
			(size 0 0)
			(layers "B.Cu" "B.Mask" "B.Paste")
			(net "CPU1_CORETYPE1")
		)
	)
	(footprint ""
		(layer "B.Cu")
		(at 303.390808 -398.942052 90)
		(property "Reference" "C561"
			(at 0 0 90)
			(layer "B.SilkS")
			(hide yes)
			(effects
				(font
					(size 1.27 1.27)
				)
				(justify mirror)
			)
		)
		(property "Value" ""
			(at 0 0 90)
			(layer "B.Fab")
			(effects
				(font
					(size 1.27 1.27)
				)
				(justify mirror)
			)
		)
		(duplicate_pad_numbers_are_jumpers no)
		(fp_line
			(start 0.7874 -0.4064)
			(end -0.7874 -0.4064)
			(stroke
				(width 0.1524)
				(type default)
			)
			(layer "B.SilkS")
		)
		(fp_line
			(start -0.7874 -0.4064)
			(end -0.7874 0.4064)
			(stroke
				(width 0.1524)
				(type default)
			)
			(layer "B.SilkS")
		)
		(fp_line
			(start 0.7874 0.4064)
			(end 0.7874 -0.4064)
			(stroke
				(width 0.1524)
				(type default)
			)
			(layer "B.SilkS")
		)
		(fp_line
			(start -0.7874 0.4064)
			(end 0.7874 0.4064)
			(stroke
				(width 0.1524)
				(type default)
			)
			(layer "B.SilkS")
		)
		(fp_line
			(start 0.67945 -0.305054)
			(end 0.12065 -0.305054)
			(stroke
				(width 0.1)
				(type default)
			)
			(layer "B.Fab")
		)
		(fp_line
			(start 0.12065 -0.305054)
			(end 0.12065 -0.2794)
			(stroke
				(width 0.1)
				(type default)
			)
			(layer "B.Fab")
		)
		(fp_line
			(start -0.12065 -0.3048)
			(end -0.67945 -0.3048)
			(stroke
				(width 0.1)
				(type default)
			)
			(layer "B.Fab")
		)
		(fp_line
			(start -0.67945 -0.3048)
			(end -0.67945 0.3048)
			(stroke
				(width 0.1)
				(type default)
			)
			(layer "B.Fab")
		)
		(fp_line
			(start 0.12065 -0.2794)
			(end -0.12065 -0.2794)
			(stroke
				(width 0.1)
				(type default)
			)
			(layer "B.Fab")
		)
		(fp_line
			(start -0.12065 -0.2794)
			(end -0.12065 -0.3048)
			(stroke
				(width 0.1)
				(type default)
			)
			(layer "B.Fab")
		)
		(fp_line
			(start 0.12065 0.2794)
			(end 0.12065 0.3048)
			(stroke
				(width 0.1)
				(type default)
			)
			(layer "B.Fab")
		)
		(fp_line
			(start -0.120396 0.2794)
			(end 0.12065 0.2794)
			(stroke
				(width 0.1)
				(type default)
			)
			(layer "B.Fab")
		)
		(fp_line
			(start 0.67945 0.3048)
			(end 0.67945 -0.305054)
			(stroke
				(width 0.1)
				(type default)
			)
			(layer "B.Fab")
		)
		(fp_line
			(start 0.12065 0.3048)
			(end 0.67945 0.3048)
			(stroke
				(width 0.1)
				(type default)
			)
			(layer "B.Fab")
		)
		(fp_line
			(start -0.120396 0.3048)
			(end -0.120396 0.2794)
			(stroke
				(width 0.1)
				(type default)
			)
			(layer "B.Fab")
		)
		(fp_line
			(start -0.67945 0.3048)
			(end -0.120396 0.3048)
			(stroke
				(width 0.1)
				(type default)
			)
			(layer "B.Fab")
		)
		(pad "1" smd circle
			(at 0.40005 0 270)
			(size 0 0)
			(layers "B.Cu" "B.Mask" "B.Paste")
			(net "P0V9_CPU0_RT0_2A")
		)
		(pad "2" smd circle
			(at -0.40005 0 270)
			(size 0 0)
			(layers "B.Cu" "B.Mask" "B.Paste")
			(net "GND")
		)
	)
	(footprint ""
		(layer "B.Cu")
		(at 187.871608 -100.290376 -90)
		(property "Reference" "R275"
			(at 0 0 90)
			(layer "B.SilkS")
			(hide yes)
			(effects
				(font
					(size 1.27 1.27)
				)
				(justify mirror)
			)
		)
		(property "Value" ""
			(at 0 0 90)
			(layer "B.Fab")
			(effects
				(font
					(size 1.27 1.27)
				)
				(justify mirror)
			)
		)
		(duplicate_pad_numbers_are_jumpers no)
		(fp_line
			(start -0.7874 0.4064)
			(end 0.7874 0.4064)
			(stroke
				(width 0.1524)
				(type default)
			)
			(layer "B.SilkS")
		)
		(fp_line
			(start 0.7874 0.4064)
			(end 0.7874 -0.4064)
			(stroke
				(width 0.1524)
				(type default)
			)
			(layer "B.SilkS")
		)
		(fp_line
			(start -0.7874 -0.4064)
			(end -0.7874 0.4064)
			(stroke
				(width 0.1524)
				(type default)
			)
			(layer "B.SilkS")
		)
		(fp_line
			(start 0.7874 -0.4064)
			(end -0.7874 -0.4064)
			(stroke
				(width 0.1524)
				(type default)
			)
			(layer "B.SilkS")
		)
		(fp_line
			(start -0.67945 0.3048)
			(end -0.120396 0.3048)
			(stroke
				(width 0.1)
				(type default)
			)
			(layer "B.Fab")
		)
		(fp_line
			(start -0.120396 0.3048)
			(end -0.120396 0.2794)
			(stroke
				(width 0.1)
				(type default)
			)
			(layer "B.Fab")
		)
		(fp_line
			(start 0.12065 0.3048)
			(end 0.67945 0.3048)
			(stroke
				(width 0.1)
				(type default)
			)
			(layer "B.Fab")
		)
		(fp_line
			(start 0.67945 0.3048)
			(end 0.67945 -0.305054)
			(stroke
				(width 0.1)
				(type default)
			)
			(layer "B.Fab")
		)
		(fp_line
			(start -0.120396 0.2794)
			(end 0.12065 0.2794)
			(stroke
				(width 0.1)
				(type default)
			)
			(layer "B.Fab")
		)
		(fp_line
			(start 0.12065 0.2794)
			(end 0.12065 0.3048)
			(stroke
				(width 0.1)
				(type default)
			)
			(layer "B.Fab")
		)
		(fp_line
			(start -0.12065 -0.2794)
			(end -0.12065 -0.3048)
			(stroke
				(width 0.1)
				(type default)
			)
			(layer "B.Fab")
		)
		(fp_line
			(start 0.12065 -0.2794)
			(end -0.12065 -0.2794)
			(stroke
				(width 0.1)
				(type default)
			)
			(layer "B.Fab")
		)
		(fp_line
			(start -0.67945 -0.3048)
			(end -0.67945 0.3048)
			(stroke
				(width 0.1)
				(type default)
			)
			(layer "B.Fab")
		)
		(fp_line
			(start -0.12065 -0.3048)
			(end -0.67945 -0.3048)
			(stroke
				(width 0.1)
				(type default)
			)
			(layer "B.Fab")
		)
		(fp_line
			(start 0.12065 -0.305054)
			(end 0.12065 -0.2794)
			(stroke
				(width 0.1)
				(type default)
			)
			(layer "B.Fab")
		)
		(fp_line
			(start 0.67945 -0.305054)
			(end 0.12065 -0.305054)
			(stroke
				(width 0.1)
				(type default)
			)
			(layer "B.Fab")
		)
		(pad "1" smd circle
			(at 0.40005 0 90)
			(size 0 0)
			(layers "B.Cu" "B.Mask" "B.Paste")
			(net "CLR_CMOS")
		)
		(pad "2" smd circle
			(at -0.40005 0 90)
			(size 0 0)
			(layers "B.Cu" "B.Mask" "B.Paste")
			(net "FM_CLR_CMOS")
		)
	)
	(footprint ""
		(layer "B.Cu")
		(at 367.741454 -249.36831)
		(property "Reference" "C2173"
			(at 0 0 0)
			(layer "B.SilkS")
			(hide yes)
			(effects
				(font
					(size 1.27 1.27)
				)
				(justify mirror)
			)
		)
		(property "Value" ""
			(at 0 0 0)
			(layer "B.Fab")
			(effects
				(font
					(size 1.27 1.27)
				)
				(justify mirror)
			)
		)
		(duplicate_pad_numbers_are_jumpers no)
		(fp_line
			(start -0.7874 -0.4064)
			(end -0.7874 0.4064)
			(stroke
				(width 0.1524)
				(type default)
			)
			(layer "B.SilkS")
		)
		(fp_line
			(start -0.7874 0.4064)
			(end 0.7874 0.4064)
			(stroke
				(width 0.1524)
				(type default)
			)
			(layer "B.SilkS")
		)
		(fp_line
			(start 0.7874 -0.4064)
			(end -0.7874 -0.4064)
			(stroke
				(width 0.1524)
				(type default)
			)
			(layer "B.SilkS")
		)
		(fp_line
			(start 0.7874 0.4064)
			(end 0.7874 -0.4064)
			(stroke
				(width 0.1524)
				(type default)
			)
			(layer "B.SilkS")
		)
		(fp_line
			(start -0.67945 -0.3048)
			(end -0.67945 0.3048)
			(stroke
				(width 0.1)
				(type default)
			)
			(layer "B.Fab")
		)
		(fp_line
			(start -0.67945 0.3048)
			(end -0.120396 0.3048)
			(stroke
				(width 0.1)
				(type default)
			)
			(layer "B.Fab")
		)
		(fp_line
			(start -0.12065 -0.3048)
			(end -0.67945 -0.3048)
			(stroke
				(width 0.1)
				(type default)
			)
			(layer "B.Fab")
		)
		(fp_line
			(start -0.12065 -0.2794)
			(end -0.12065 -0.3048)
			(stroke
				(width 0.1)
				(type default)
			)
			(layer "B.Fab")
		)
		(fp_line
			(start -0.120396 0.2794)
			(end 0.12065 0.2794)
			(stroke
				(width 0.1)
				(type default)
			)
			(layer "B.Fab")
		)
		(fp_line
			(start -0.120396 0.3048)
			(end -0.120396 0.2794)
			(stroke
				(width 0.1)
				(type default)
			)
			(layer "B.Fab")
		)
		(fp_line
			(start 0.12065 -0.305054)
			(end 0.12065 -0.2794)
			(stroke
				(width 0.1)
				(type default)
			)
			(layer "B.Fab")
		)
		(fp_line
			(start 0.12065 -0.2794)
			(end -0.12065 -0.2794)
			(stroke
				(width 0.1)
				(type default)
			)
			(layer "B.Fab")
		)
		(fp_line
			(start 0.12065 0.2794)
			(end 0.12065 0.3048)
			(stroke
				(width 0.1)
				(type default)
			)
			(layer "B.Fab")
		)
		(fp_line
			(start 0.12065 0.3048)
			(end 0.67945 0.3048)
			(stroke
				(width 0.1)
				(type default)
			)
			(layer "B.Fab")
		)
		(fp_line
			(start 0.67945 -0.305054)
			(end 0.12065 -0.305054)
			(stroke
				(width 0.1)
				(type default)
			)
			(layer "B.Fab")
		)
		(fp_line
			(start 0.67945 0.3048)
			(end 0.67945 -0.305054)
			(stroke
				(width 0.1)
				(type default)
			)
			(layer "B.Fab")
		)
		(pad "1" smd circle
			(at 0.40005 0 180)
			(size 0 0)
			(layers "B.Cu" "B.Mask" "B.Paste")
			(net "PVDDCR_CPU0_P0")
		)
		(pad "2" smd circle
			(at -0.40005 0 180)
			(size 0 0)
			(layers "B.Cu" "B.Mask" "B.Paste")
			(net "GND")
		)
	)
	(footprint ""
		(layer "B.Cu")
		(at 398.473168 -45.272706 180)
		(property "Reference" ""
			(at 0 0 0)
			(layer "B.SilkS")
			(hide yes)
			(effects
				(font
					(size 1.27 1.27)
				)
				(justify mirror)
			)
		)
		(property "Value" ""
			(at 0 0 0)
			(layer "B.Fab")
			(effects
				(font
					(size 1.27 1.27)
				)
				(justify mirror)
			)
		)
		(duplicate_pad_numbers_are_jumpers no)
		(pad "1" smd circle
			(at 0 0)
			(size 0.9906 0.9906)
			(layers "B.Cu" "B.Mask" "B.Paste")
			(net "Net_2234")
		)
		(zone
			(layer "B.Cu")
			(hatch none 0.5)
			(connect_pads
				(clearance 0)
			)
			(min_thickness 0.25)
			(keepout
				(tracks not_allowed)
				(vias allowed)
				(pads allowed)
				(copperpour not_allowed)
				(footprints allowed)
			)
			(placement
				(enabled no)
				(sheetname "")
			)
			(fill
				(thermal_gap 0.5)
				(thermal_bridge_width 0.5)
				(island_removal_mode 0)
			)
			(polygon
				(pts
					(arc
						(start 400.098768 -45.272706)
						(mid 396.847568 -45.272706)
						(end 400.098768 -45.272706)
					)
				)
			)
		)
	)
	(footprint ""
		(layer "B.Cu")
		(at 374.770142 -149.055582 90)
		(property "Reference" "PR306"
			(at 0 0 90)
			(layer "B.SilkS")
			(hide yes)
			(effects
				(font
					(size 1.27 1.27)
				)
				(justify mirror)
			)
		)
		(property "Value" ""
			(at 0 0 90)
			(layer "B.Fab")
			(effects
				(font
					(size 1.27 1.27)
				)
				(justify mirror)
			)
		)
		(duplicate_pad_numbers_are_jumpers no)
		(fp_line
			(start 0.7874 -0.4064)
			(end -0.7874 -0.4064)
			(stroke
				(width 0.1524)
				(type default)
			)
			(layer "B.SilkS")
		)
		(fp_line
			(start -0.7874 -0.4064)
			(end -0.7874 0.4064)
			(stroke
				(width 0.1524)
				(type default)
			)
			(layer "B.SilkS")
		)
		(fp_line
			(start 0.7874 0.4064)
			(end 0.7874 -0.4064)
			(stroke
				(width 0.1524)
				(type default)
			)
			(layer "B.SilkS")
		)
		(fp_line
			(start -0.7874 0.4064)
			(end 0.7874 0.4064)
			(stroke
				(width 0.1524)
				(type default)
			)
			(layer "B.SilkS")
		)
		(fp_line
			(start 0.67945 -0.305054)
			(end 0.12065 -0.305054)
			(stroke
				(width 0.1)
				(type default)
			)
			(layer "B.Fab")
		)
		(fp_line
			(start 0.12065 -0.305054)
			(end 0.12065 -0.2794)
			(stroke
				(width 0.1)
				(type default)
			)
			(layer "B.Fab")
		)
		(fp_line
			(start -0.12065 -0.3048)
			(end -0.67945 -0.3048)
			(stroke
				(width 0.1)
				(type default)
			)
			(layer "B.Fab")
		)
		(fp_line
			(start -0.67945 -0.3048)
			(end -0.67945 0.3048)
			(stroke
				(width 0.1)
				(type default)
			)
			(layer "B.Fab")
		)
		(fp_line
			(start 0.12065 -0.2794)
			(end -0.12065 -0.2794)
			(stroke
				(width 0.1)
				(type default)
			)
			(layer "B.Fab")
		)
		(fp_line
			(start -0.12065 -0.2794)
			(end -0.12065 -0.3048)
			(stroke
				(width 0.1)
				(type default)
			)
			(layer "B.Fab")
		)
		(fp_line
			(start 0.12065 0.2794)
			(end 0.12065 0.3048)
			(stroke
				(width 0.1)
				(type default)
			)
			(layer "B.Fab")
		)
		(fp_line
			(start -0.120396 0.2794)
			(end 0.12065 0.2794)
			(stroke
				(width 0.1)
				(type default)
			)
			(layer "B.Fab")
		)
		(fp_line
			(start 0.67945 0.3048)
			(end 0.67945 -0.305054)
			(stroke
				(width 0.1)
				(type default)
			)
			(layer "B.Fab")
		)
		(fp_line
			(start 0.12065 0.3048)
			(end 0.67945 0.3048)
			(stroke
				(width 0.1)
				(type default)
			)
			(layer "B.Fab")
		)
		(fp_line
			(start -0.120396 0.3048)
			(end -0.120396 0.2794)
			(stroke
				(width 0.1)
				(type default)
			)
			(layer "B.Fab")
		)
		(fp_line
			(start -0.67945 0.3048)
			(end -0.120396 0.3048)
			(stroke
				(width 0.1)
				(type default)
			)
			(layer "B.Fab")
		)
		(pad "1" smd circle
			(at 0.40005 0 270)
			(size 0 0)
			(layers "B.Cu" "B.Mask" "B.Paste")
			(net "VSENSE_PVDDCR_CPU0_P0_DP")
		)
		(pad "2" smd circle
			(at -0.40005 0 270)
			(size 0 0)
			(layers "B.Cu" "B.Mask" "B.Paste")
			(net "VSENSE_PVDDCR_CPU0_P0_VSEN0")
		)
	)
)
